FILE_TYPE = CONNECTIVITY;
{Allegro Design Entry HDL 17.4-2019 S026 (4007227) 1/17/2022}
"PAGE_NUMBER" = 7;
0"NC";
END.
